(kicad_pcb
	(version 20241229)
	(generator "pcbnew")
	(generator_version "9.0")
	(general
		(thickness 1.61)
		(legacy_teardrops no)
	)
	(paper "A3")
	(title_block
		(title "RDIMM DDR5 Tester")
		(date "2026-05-21")
		(rev "2.2.0")
		(company "Antmicro")
		(comment 9 "footprints 227-229 of 796")
	)
	(layers
		(0 "F.Cu" signal)
		(4 "In1.Cu" power)
		(6 "In2.Cu" mixed)
		(8 "In3.Cu" power)
		(10 "In4.Cu" mixed)
		(12 "In5.Cu" power)
		(14 "In6.Cu" mixed)
		(16 "In7.Cu" power)
		(18 "In8.Cu" power)
		(20 "In9.Cu" mixed)
		(22 "In10.Cu" power)
		(2 "B.Cu" signal)
		(9 "F.Adhes" user "F.Adhesive")
		(11 "B.Adhes" user "B.Adhesive")
		(13 "F.Paste" user)
		(15 "B.Paste" user)
		(5 "F.SilkS" user "F.Silkscreen")
		(7 "B.SilkS" user "B.Silkscreen")
		(1 "F.Mask" user)
		(3 "B.Mask" user)
		(17 "Dwgs.User" user "User.Drawings")
		(19 "Cmts.User" user "User.Comments")
		(21 "Eco1.User" user "User.Eco1")
		(23 "Eco2.User" user "User.Eco2")
		(25 "Edge.Cuts" user)
		(27 "Margin" user)
		(31 "F.CrtYd" user "F.Courtyard")
		(29 "B.CrtYd" user "B.Courtyard")
		(35 "F.Fab" user)
		(33 "B.Fab" user)
	)
	(footprint "antmicro-footprints:USON-10_2.5x1mm_P0.5mm"
		(layer "F.Cu")
		(at 108.824499 143.749 180)
		(descr "USON-10 2.5x1mm_ Pitch 0.5mm")
		(tags "USON-10 2.5x1mm Pitch 0.5mm")
		(property "Reference" "U8"
			(at -2.025501 -0.151 90)
			(layer "F.SilkS")
			(effects
				(font
					(size 0.7 0.7)
					(thickness 0.15)
				)
				(justify right bottom)
			)
		)
		(property "Value" "TPD4E05U06QDQARQ1"
			(at 0.018 2.499 0)
			(layer "F.Fab")
			(effects
				(font
					(size 0.7 0.7)
					(thickness 0.15)
				)
				(justify right bottom)
			)
		)
		(property "Datasheet" "https://www.ti.com/lit/ds/symlink/tpd4e05u06-q1.pdf?HQS=dis-mous-null-mousermode-dsf-pf-null-wwe&ts=1663591265741&ref_url=https%253A%252F%252Fwww.mouser.com%252F"
			(at 0 0 180)
			(layer "F.Fab")
			(hide yes)
			(effects
				(font
					(size 1.27 1.27)
					(thickness 0.15)
				)
			)
		)
		(property "MPN" "TPD4E05U06QDQARQ1"
			(at 0 0 180)
			(unlocked yes)
			(layer "F.Fab")
			(hide yes)
			(effects
				(font
					(size 1 1)
					(thickness 0.15)
				)
			)
		)
		(property "Manufacturer" "Texas Instruments"
			(at 0 0 180)
			(unlocked yes)
			(layer "F.Fab")
			(hide yes)
			(effects
				(font
					(size 1 1)
					(thickness 0.15)
				)
			)
		)
		(property "Author" "Antmicro"
			(at 0 0 180)
			(unlocked yes)
			(layer "F.Fab")
			(hide yes)
			(effects
				(font
					(size 1 1)
					(thickness 0.15)
				)
			)
		)
		(property "License" "Apache-2.0"
			(at 0 0 180)
			(unlocked yes)
			(layer "F.Fab")
			(hide yes)
			(effects
				(font
					(size 1 1)
					(thickness 0.15)
				)
			)
		)
		(sheetname "/Debug FTDI + VNA/")
		(sheetfile "debug-ftdi.kicad_sch")
		(attr smd)
		(fp_line
			(start 0.498 1.398)
			(end -0.5 1.398)
			(stroke
				(width 0.15)
				(type solid)
			)
			(layer "F.SilkS")
		)
		(fp_line
			(start 0.498 -1.401)
			(end -0.5 -1.401)
			(stroke
				(width 0.15)
				(type solid)
			)
			(layer "F.SilkS")
		)
		(fp_circle
			(center -0.68 -1.27)
			(end -0.63 -1.27)
			(stroke
				(width 0.15)
				(type solid)
			)
			(fill yes)
			(layer "F.SilkS")
		)
		(fp_rect
			(start -0.8 -1.5)
			(end 0.8 1.499)
			(stroke
				(width 0.05)
				(type solid)
			)
			(fill no)
			(layer "F.CrtYd")
		)
		(fp_line
			(start 0.498 -1.25)
			(end 0.498 1.249)
			(stroke
				(width 0.15)
				(type solid)
			)
			(layer "F.Fab")
		)
		(fp_line
			(start 0.498 -1.25)
			(end -0.25 -1.25)
			(stroke
				(width 0.15)
				(type solid)
			)
			(layer "F.Fab")
		)
		(fp_line
			(start -0.25 -1.25)
			(end -0.5 -1)
			(stroke
				(width 0.15)
				(type solid)
			)
			(layer "F.Fab")
		)
		(fp_line
			(start -0.5 1.249)
			(end 0.498 1.249)
			(stroke
				(width 0.15)
				(type solid)
			)
			(layer "F.Fab")
		)
		(fp_line
			(start -0.5 -1)
			(end -0.5 1.249)
			(stroke
				(width 0.15)
				(type solid)
			)
			(layer "F.Fab")
		)
		(fp_text user "${REFERENCE}"
			(at -0.802 4.498 180)
			(layer "F.Fab")
			(effects
				(font
					(size 0.7 0.7)
					(thickness 0.15)
				)
				(justify left bottom)
			)
		)
		(fp_text user "Author: Antmicro"
			(at -0.802 5.7 180)
			(layer "F.Fab")
			(effects
				(font
					(size 0.7 0.7)
					(thickness 0.15)
				)
				(justify left bottom)
			)
		)
		(fp_text user "License: Apache-2.0"
			(at -0.802 6.9 180)
			(layer "F.Fab")
			(effects
				(font
					(size 0.7 0.7)
					(thickness 0.15)
				)
				(justify left bottom)
			)
		)
		(pad "1" smd roundrect
			(at -0.387 -1 90)
			(size 0.25 0.55)
			(layers "F.Cu" "F.Mask" "F.Paste")
			(roundrect_rratio 0.25)
			(net 366 "/Debug FTDI + VNA/CC2")
			(pintype "passive")
		)
		(pad "2" smd roundrect
			(at -0.387 -0.5 90)
			(size 0.25 0.55)
			(layers "F.Cu" "F.Mask" "F.Paste")
			(roundrect_rratio 0.25)
			(net 364 "/Debug FTDI + VNA/DBG_USB_P")
			(pintype "passive")
		)
		(pad "3" smd roundrect
			(at -0.387 0 90)
			(size 0.4 0.55)
			(layers "F.Cu" "F.Mask" "F.Paste")
			(roundrect_rratio 0.25)
			(net 1 "GND")
			(pintype "power_in")
		)
		(pad "4" smd roundrect
			(at -0.387 0.498 90)
			(size 0.25 0.55)
			(layers "F.Cu" "F.Mask" "F.Paste")
			(roundrect_rratio 0.25)
			(net 365 "/Debug FTDI + VNA/DBG_USB_N")
			(pintype "passive")
		)
		(pad "5" smd roundrect
			(at -0.387 0.998 90)
			(size 0.25 0.55)
			(layers "F.Cu" "F.Mask" "F.Paste")
			(roundrect_rratio 0.25)
			(net 363 "/Debug FTDI + VNA/CC1")
			(pintype "passive")
		)
		(pad "6" smd roundrect
			(at 0.385 0.998 90)
			(size 0.25 0.55)
			(layers "F.Cu" "F.Mask" "F.Paste")
			(roundrect_rratio 0.25)
			(net 363 "/Debug FTDI + VNA/CC1")
			(pintype "passive")
		)
		(pad "7" smd roundrect
			(at 0.385 0.498 90)
			(size 0.25 0.55)
			(layers "F.Cu" "F.Mask" "F.Paste")
			(roundrect_rratio 0.25)
			(net 365 "/Debug FTDI + VNA/DBG_USB_N")
			(pintype "passive")
		)
		(pad "8" smd roundrect
			(at 0.385 0 90)
			(size 0.4 0.55)
			(layers "F.Cu" "F.Mask" "F.Paste")
			(roundrect_rratio 0.25)
			(net 1 "GND")
			(pintype "passive")
		)
		(pad "9" smd roundrect
			(at 0.385 -0.5 90)
			(size 0.25 0.55)
			(layers "F.Cu" "F.Mask" "F.Paste")
			(roundrect_rratio 0.25)
			(net 364 "/Debug FTDI + VNA/DBG_USB_P")
			(pintype "passive")
		)
		(pad "10" smd roundrect
			(at 0.385 -1 90)
			(size 0.25 0.55)
			(layers "F.Cu" "F.Mask" "F.Paste")
			(roundrect_rratio 0.25)
			(net 366 "/Debug FTDI + VNA/CC2")
			(pintype "passive")
		)
	)
	(footprint "antmicro-footprints:LED_0402_1005Metric_G"
		(layer "F.Cu")
		(at 243.051 101.6)
		(property "Reference" "D22"
			(at 0 -0.6 0)
			(unlocked yes)
			(layer "F.SilkS")
			(hide yes)
			(effects
				(font
					(size 0.7 0.7)
					(thickness 0.15)
				)
				(justify left bottom)
			)
		)
		(property "Value" "LED_G_0402_VLMTG1500-GS08"
			(at 0 1.5 0)
			(unlocked yes)
			(layer "F.Fab")
			(effects
				(font
					(size 0.7 0.7)
					(thickness 0.15)
				)
				(justify left bottom)
			)
		)
		(property "Datasheet" "https://www.vishay.com/docs/82554/vlmo1500.pdf"
			(at 0 0 0)
			(layer "F.Fab")
			(hide yes)
			(effects
				(font
					(size 1.27 1.27)
					(thickness 0.15)
				)
			)
		)
		(property "MPN" "VLMTG1500-GS08"
			(at 0 0 0)
			(unlocked yes)
			(layer "F.Fab")
			(hide yes)
			(effects
				(font
					(size 1 1)
					(thickness 0.15)
				)
			)
		)
		(property "Manufacturer" "Vishay"
			(at 0 0 0)
			(unlocked yes)
			(layer "F.Fab")
			(hide yes)
			(effects
				(font
					(size 1 1)
					(thickness 0.15)
				)
			)
		)
		(property "Color" "Green"
			(at 0 0 0)
			(unlocked yes)
			(layer "F.Fab")
			(hide yes)
			(effects
				(font
					(size 1 1)
					(thickness 0.15)
				)
			)
		)
		(property "Author" "Antmicro"
			(at 0 0 0)
			(unlocked yes)
			(layer "F.Fab")
			(hide yes)
			(effects
				(font
					(size 1 1)
					(thickness 0.15)
				)
			)
		)
		(property "License" "Apache-2.0"
			(at 0 0 0)
			(unlocked yes)
			(layer "F.Fab")
			(hide yes)
			(effects
				(font
					(size 1 1)
					(thickness 0.15)
				)
			)
		)
		(sheetname "/DDR5 RDIMM/")
		(sheetfile "ddr5-rdimm.kicad_sch")
		(attr smd)
		(fp_line
			(start -0.9 -0.4)
			(end -0.9 0.4)
			(stroke
				(width 0.15)
				(type solid)
			)
			(layer "F.SilkS")
		)
		(fp_line
			(start -0.175 -0.4)
			(end 0.175 -0.4)
			(stroke
				(width 0.15)
				(type solid)
			)
			(layer "F.SilkS")
		)
		(fp_line
			(start -0.175 0.4)
			(end 0.175 0.4)
			(stroke
				(width 0.15)
				(type solid)
			)
			(layer "F.SilkS")
		)
		(fp_rect
			(start -0.925 -0.47)
			(end 0.925 0.47)
			(stroke
				(width 0.05)
				(type default)
			)
			(fill no)
			(layer "F.CrtYd")
		)
		(fp_line
			(start -0.489 -0.248)
			(end -0.489 0.26)
			(stroke
				(width 0.15)
				(type solid)
			)
			(layer "F.Fab")
		)
		(fp_line
			(start -0.489 -0.248)
			(end -0.489 0.26)
			(stroke
				(width 0.15)
				(type solid)
			)
			(layer "F.Fab")
		)
		(fp_line
			(start -0.489 0.26)
			(end -0.158 0.26)
			(stroke
				(width 0.15)
				(type solid)
			)
			(layer "F.Fab")
		)
		(fp_line
			(start -0.489 0.26)
			(end 0.501 0.26)
			(stroke
				(width 0.15)
				(type solid)
			)
			(layer "F.Fab")
		)
		(fp_line
			(start -0.173 -0.202)
			(end -0.173 0.102)
			(stroke
				(width 0.15)
				(type solid)
			)
			(layer "F.Fab")
		)
		(fp_line
			(start -0.173 0.202)
			(end -0.173 0.102)
			(stroke
				(width 0.15)
				(type solid)
			)
			(layer "F.Fab")
		)
		(fp_line
			(start -0.158 -0.248)
			(end -0.489 -0.248)
			(stroke
				(width 0.15)
				(type solid)
			)
			(layer "F.Fab")
		)
		(fp_line
			(start -0.158 0.26)
			(end -0.158 -0.248)
			(stroke
				(width 0.15)
				(type solid)
			)
			(layer "F.Fab")
		)
		(fp_line
			(start -0.074 0)
			(end 0.228 0.202)
			(stroke
				(width 0.15)
				(type solid)
			)
			(layer "F.Fab")
		)
		(fp_line
			(start 0.172 -0.248)
			(end 0.172 0.26)
			(stroke
				(width 0.15)
				(type solid)
			)
			(layer "F.Fab")
		)
		(fp_line
			(start 0.172 0.26)
			(end 0.501 0.26)
			(stroke
				(width 0.15)
				(type solid)
			)
			(layer "F.Fab")
		)
		(fp_line
			(start 0.228 -0.202)
			(end -0.074 0)
			(stroke
				(width 0.15)
				(type solid)
			)
			(layer "F.Fab")
		)
		(fp_line
			(start 0.228 0)
			(end 0.228 -0.202)
			(stroke
				(width 0.15)
				(type solid)
			)
			(layer "F.Fab")
		)
		(fp_line
			(start 0.228 0.202)
			(end 0.228 0)
			(stroke
				(width 0.15)
				(type solid)
			)
			(layer "F.Fab")
		)
		(fp_line
			(start 0.501 -0.248)
			(end -0.489 -0.248)
			(stroke
				(width 0.15)
				(type solid)
			)
			(layer "F.Fab")
		)
		(fp_line
			(start 0.501 -0.248)
			(end 0.172 -0.248)
			(stroke
				(width 0.15)
				(type solid)
			)
			(layer "F.Fab")
		)
		(fp_line
			(start 0.501 0.26)
			(end 0.501 -0.248)
			(stroke
				(width 0.15)
				(type solid)
			)
			(layer "F.Fab")
		)
		(fp_line
			(start 0.501 0.26)
			(end 0.501 -0.248)
			(stroke
				(width 0.15)
				(type solid)
			)
			(layer "F.Fab")
		)
		(fp_text user "Author: Antmicro"
			(at 0 4.15 0)
			(layer "F.Fab")
			(effects
				(font
					(size 0.7 0.7)
					(thickness 0.15)
				)
				(justify left bottom)
			)
		)
		(fp_text user "License: Apache-2.0"
			(at 0 5.35 0)
			(layer "F.Fab")
			(effects
				(font
					(size 0.7 0.7)
					(thickness 0.15)
				)
				(justify left bottom)
			)
		)
		(fp_text user "${REFERENCE}"
			(at 0 2.95 0)
			(unlocked yes)
			(layer "F.Fab")
			(effects
				(font
					(size 0.7 0.7)
					(thickness 0.15)
				)
				(justify left bottom)
			)
		)
		(pad "1" smd roundrect
			(at -0.48 0)
			(size 0.59 0.64)
			(layers "F.Cu" "F.Mask" "F.Paste")
			(roundrect_rratio 0.25)
			(net 805 "Net-(D22-C)")
			(pinfunction "C")
			(pintype "passive")
		)
		(pad "2" smd roundrect
			(at 0.48 0)
			(size 0.59 0.64)
			(layers "F.Cu" "F.Mask" "F.Paste")
			(roundrect_rratio 0.25)
			(net 803 "/DDR5 RDIMM/VIN_MGMT")
			(pinfunction "A")
			(pintype "passive")
		)
	)
	(footprint "antmicro-footprints:SW_KMR211NGLFS_SMD"
		(layer "F.Cu")
		(at 260.573 137.475 90)
		(property "Reference" "SW2"
			(at -1.1 -2 90)
			(layer "F.SilkS")
			(hide yes)
			(effects
				(font
					(size 0.7 0.7)
					(thickness 0.15)
				)
				(justify left bottom)
			)
		)
		(property "Value" "SW_KMR211NGLFS_SMD"
			(at 0 2.8 90)
			(layer "F.Fab")
			(effects
				(font
					(size 0.7 0.7)
					(thickness 0.15)
				)
				(justify left bottom)
			)
		)
		(property "Datasheet" "http://www.farnell.com/datasheets/2631211.pdf"
			(at 0 0 90)
			(layer "F.Fab")
			(hide yes)
			(effects
				(font
					(size 1.27 1.27)
					(thickness 0.15)
				)
			)
		)
		(property "MPN" "KMR211NGLFS"
			(at 0 0 90)
			(unlocked yes)
			(layer "F.Fab")
			(hide yes)
			(effects
				(font
					(size 1 1)
					(thickness 0.15)
				)
			)
		)
		(property "Manufacturer" "C&K"
			(at 0 0 90)
			(unlocked yes)
			(layer "F.Fab")
			(hide yes)
			(effects
				(font
					(size 1 1)
					(thickness 0.15)
				)
			)
		)
		(property "Author" "Antmicro"
			(at 0 0 90)
			(unlocked yes)
			(layer "F.Fab")
			(hide yes)
			(effects
				(font
					(size 1 1)
					(thickness 0.15)
				)
			)
		)
		(property "License" "Apache-2.0"
			(at 0 0 90)
			(unlocked yes)
			(layer "F.Fab")
			(hide yes)
			(effects
				(font
					(size 1 1)
					(thickness 0.15)
				)
			)
		)
		(sheetname "/FPGA Config/")
		(sheetfile "fpga-config.kicad_sch")
		(attr smd)
		(fp_line
			(start 2.101 -1.6)
			(end -2.1 -1.6)
			(stroke
				(width 0.15)
				(type solid)
			)
			(layer "F.SilkS")
		)
		(fp_line
			(start -2.1 -1.6)
			(end -2.1 -1.499)
			(stroke
				(width 0.15)
				(type solid)
			)
			(layer "F.SilkS")
		)
		(fp_line
			(start 2.101 -1.58)
			(end 2.101 -1.459)
			(stroke
				(width 0.15)
				(type solid)
			)
			(layer "F.SilkS")
		)
		(fp_line
			(start 2.101 1.601)
			(end 2.101 1.48)
			(stroke
				(width 0.15)
				(type solid)
			)
			(layer "F.SilkS")
		)
		(fp_line
			(start 2.101 1.601)
			(end -2.1 1.601)
			(stroke
				(width 0.15)
				(type solid)
			)
			(layer "F.SilkS")
		)
		(fp_line
			(start -2.1 1.601)
			(end -2.1 1.48)
			(stroke
				(width 0.15)
				(type solid)
			)
			(layer "F.SilkS")
		)
		(fp_rect
			(start 2.751 1.75)
			(end -2.748 -1.749)
			(stroke
				(width 0.05)
				(type solid)
			)
			(fill no)
			(layer "F.CrtYd")
		)
		(fp_line
			(start 2.101 -1.6)
			(end -2.1 -1.6)
			(stroke
				(width 0.15)
				(type solid)
			)
			(layer "F.Fab")
		)
		(fp_line
			(start -2.1 -1.6)
			(end -2.1 1.601)
			(stroke
				(width 0.15)
				(type solid)
			)
			(layer "F.Fab")
		)
		(fp_line
			(start -0.248 -0.8)
			(end 0.25 -0.8)
			(stroke
				(width 0.15)
				(type solid)
			)
			(layer "F.Fab")
		)
		(fp_line
			(start 0.25 0.802)
			(end -0.248 0.802)
			(stroke
				(width 0.15)
				(type solid)
			)
			(layer "F.Fab")
		)
		(fp_line
			(start 2.101 1.601)
			(end 2.101 -1.6)
			(stroke
				(width 0.15)
				(type solid)
			)
			(layer "F.Fab")
		)
		(fp_line
			(start -2.1 1.601)
			(end 2.101 1.601)
			(stroke
				(width 0.15)
				(type solid)
			)
			(layer "F.Fab")
		)
		(fp_arc
			(start 0.25 -0.8)
			(mid 1.051001 0.001)
			(end 0.25 0.802)
			(stroke
				(width 0.15)
				(type solid)
			)
			(layer "F.Fab")
		)
		(fp_arc
			(start -0.248 0.802)
			(mid -1.050001 0.001)
			(end -0.248 -0.8)
			(stroke
				(width 0.15)
				(type solid)
			)
			(layer "F.Fab")
		)
		(fp_text user "Author: Antmicro"
			(at -3 5.5 90)
			(layer "F.Fab")
			(effects
				(font
					(size 0.7 0.7)
					(thickness 0.15)
				)
				(justify left bottom)
			)
		)
		(fp_text user "License: Apache-2.0"
			(at -3 6.75 90)
			(layer "F.Fab")
			(effects
				(font
					(size 0.7 0.7)
					(thickness 0.15)
				)
				(justify left bottom)
			)
		)
		(fp_text user "${REFERENCE}"
			(at -3 4.25 90)
			(layer "F.Fab")
			(effects
				(font
					(size 0.7 0.7)
					(thickness 0.15)
				)
				(justify left bottom)
			)
		)
		(pad "1" smd rect
			(at -2.048 -0.8 270)
			(size 0.9 1)
			(layers "F.Cu" "F.Mask" "F.Paste")
			(net 357 "/FPGA Config/PROGRAM_B")
			(pinfunction "1")
			(pintype "passive")
		)
		(pad "2" smd rect
			(at 2.05 -0.8 270)
			(size 0.9 1)
			(layers "F.Cu" "F.Mask" "F.Paste")
			(net 357 "/FPGA Config/PROGRAM_B")
			(pinfunction "2")
			(pintype "passive")
		)
		(pad "3" smd rect
			(at -2.048 0.802 270)
			(size 0.9 1)
			(layers "F.Cu" "F.Mask" "F.Paste")
			(net 1 "GND")
			(pinfunction "3")
			(pintype "passive")
		)
		(pad "4" smd rect
			(at 2.05 0.802 270)
			(size 0.9 1)
			(layers "F.Cu" "F.Mask" "F.Paste")
			(net 1 "GND")
			(pinfunction "4")
			(pintype "passive")
		)
	)
)
